(kicad_pcb
	(version 20260206)
	(generator "pcbnew")
	(generator_version "10.0")
	(general
		(thickness 1.6)
		(legacy_teardrops no)
	)
	(paper "A4")
	(title_block
		(title "12092022_DA0F0TFB6D0_F0T_FAN_BOARD_MP5048_D_brd_v02_OCP.brd")
		(comment 1 "Grand Teton / footprints 387-392 of 924")
	)
	(layers
		(0 "F.Cu" signal "TOP")
		(4 "In1.Cu" signal "GND")
		(6 "In2.Cu" signal "IN1")
		(8 "In3.Cu" signal "IN2")
		(10 "In4.Cu" signal "GND1")
		(2 "B.Cu" signal "BOTTOM")
		(9 "F.Adhes" user "F.Adhesive")
		(11 "B.Adhes" user "B.Adhesive")
		(13 "F.Paste" user "Package Geometry/Pastemask Top")
		(15 "B.Paste" user "Package Geometry/Pastemask Bottom")
		(5 "F.SilkS" user "Ref Des/Silkscreen Top")
		(7 "B.SilkS" user "Ref Des/Silkscreen Bottom")
		(1 "F.Mask" user "Board Geometry/Soldermask Top")
		(3 "B.Mask" user "Board Geometry/Soldermask Bottom")
		(17 "Dwgs.User" user "User.Drawings")
		(19 "Cmts.User" user "User.Comments")
		(21 "Eco1.User" user "User.Eco1")
		(23 "Eco2.User" user "User.Eco2")
		(25 "Edge.Cuts" user "Board Geometry/Outline")
		(27 "Margin" user)
		(31 "F.CrtYd" user "Package Geometry/Place Bound Top")
		(29 "B.CrtYd" user "Package Geometry/Place Bound Bottom")
		(35 "F.Fab" user "Ref Des/Assembly Top")
		(33 "B.Fab" user "Ref Des/Assembly Bottom")
	)
	(footprint ""
		(layer "F.Cu")
		(at 19.431 -133.985 -90)
		(property "Reference" "R4848"
			(at 0 0 270)
			(layer "F.SilkS")
			(hide yes)
			(effects
				(font
					(size 1.27 1.27)
				)
			)
		)
		(property "Value" ""
			(at 0 0 270)
			(layer "F.Fab")
			(effects
				(font
					(size 1.27 1.27)
				)
			)
		)
		(duplicate_pad_numbers_are_jumpers no)
		(fp_line
			(start -0.7874 0.4064)
			(end -0.7874 -0.4064)
			(stroke
				(width 0.1524)
				(type default)
			)
			(layer "F.SilkS")
		)
		(fp_line
			(start 0.7874 0.4064)
			(end -0.7874 0.4064)
			(stroke
				(width 0.1524)
				(type default)
			)
			(layer "F.SilkS")
		)
		(fp_line
			(start -0.7874 -0.4064)
			(end 0.7874 -0.4064)
			(stroke
				(width 0.1524)
				(type default)
			)
			(layer "F.SilkS")
		)
		(fp_line
			(start 0.7874 -0.4064)
			(end 0.7874 0.4064)
			(stroke
				(width 0.1524)
				(type default)
			)
			(layer "F.SilkS")
		)
		(fp_line
			(start -0.67945 0.3048)
			(end -0.67945 -0.305054)
			(stroke
				(width 0.1)
				(type default)
			)
			(layer "F.Fab")
		)
		(fp_line
			(start -0.12065 0.3048)
			(end -0.67945 0.3048)
			(stroke
				(width 0.1)
				(type default)
			)
			(layer "F.Fab")
		)
		(fp_line
			(start 0.120396 0.3048)
			(end 0.120396 0.2794)
			(stroke
				(width 0.1)
				(type default)
			)
			(layer "F.Fab")
		)
		(fp_line
			(start 0.67945 0.3048)
			(end 0.120396 0.3048)
			(stroke
				(width 0.1)
				(type default)
			)
			(layer "F.Fab")
		)
		(fp_line
			(start -0.12065 0.2794)
			(end -0.12065 0.3048)
			(stroke
				(width 0.1)
				(type default)
			)
			(layer "F.Fab")
		)
		(fp_line
			(start 0.120396 0.2794)
			(end -0.12065 0.2794)
			(stroke
				(width 0.1)
				(type default)
			)
			(layer "F.Fab")
		)
		(fp_line
			(start -0.12065 -0.2794)
			(end 0.12065 -0.2794)
			(stroke
				(width 0.1)
				(type default)
			)
			(layer "F.Fab")
		)
		(fp_line
			(start 0.12065 -0.2794)
			(end 0.12065 -0.3048)
			(stroke
				(width 0.1)
				(type default)
			)
			(layer "F.Fab")
		)
		(fp_line
			(start 0.12065 -0.3048)
			(end 0.67945 -0.3048)
			(stroke
				(width 0.1)
				(type default)
			)
			(layer "F.Fab")
		)
		(fp_line
			(start 0.67945 -0.3048)
			(end 0.67945 0.3048)
			(stroke
				(width 0.1)
				(type default)
			)
			(layer "F.Fab")
		)
		(fp_line
			(start -0.67945 -0.305054)
			(end -0.12065 -0.305054)
			(stroke
				(width 0.1)
				(type default)
			)
			(layer "F.Fab")
		)
		(fp_line
			(start -0.12065 -0.305054)
			(end -0.12065 -0.2794)
			(stroke
				(width 0.1)
				(type default)
			)
			(layer "F.Fab")
		)
		(pad "1" smd circle
			(at -0.40005 0 270)
			(size 0 0)
			(layers "F.Cu" "F.Mask" "F.Paste")
			(net "P3V3_AUX")
		)
		(pad "2" smd circle
			(at 0.40005 0 270)
			(size 0 0)
			(layers "F.Cu" "F.Mask" "F.Paste")
			(net "MAX31790_U330_ADD0")
		)
	)
	(footprint ""
		(layer "F.Cu")
		(at 23.241 -31.369 180)
		(property "Reference" "U409"
			(at 1.4478 -1.74371 0)
			(unlocked yes)
			(layer "F.SilkS")
			(effects
				(font
					(size 0.7874 0.5842)
					(thickness 0.1524)
				)
				(justify left)
			)
		)
		(property "Value" ""
			(at 0 0 180)
			(layer "F.Fab")
			(effects
				(font
					(size 1.27 1.27)
				)
			)
		)
		(duplicate_pad_numbers_are_jumpers no)
		(fp_line
			(start 1.335278 1.100074)
			(end 1.335278 -1.100074)
			(stroke
				(width 0.1524)
				(type default)
			)
			(layer "F.SilkS")
		)
		(fp_line
			(start 1.335278 -1.100074)
			(end -1.335278 -1.100074)
			(stroke
				(width 0.1524)
				(type default)
			)
			(layer "F.SilkS")
		)
		(fp_line
			(start -1.335278 1.100074)
			(end 1.335278 1.100074)
			(stroke
				(width 0.1524)
				(type default)
			)
			(layer "F.SilkS")
		)
		(fp_line
			(start -1.335278 -1.100074)
			(end -1.335278 1.100074)
			(stroke
				(width 0.1524)
				(type default)
			)
			(layer "F.SilkS")
		)
		(fp_line
			(start 0.674878 1.100074)
			(end 0.674878 -1.100074)
			(stroke
				(width 0.1)
				(type default)
			)
			(layer "F.Fab")
		)
		(fp_line
			(start 0.674878 -1.100074)
			(end -0.674878 -1.100074)
			(stroke
				(width 0.1)
				(type default)
			)
			(layer "F.Fab")
		)
		(fp_line
			(start -0.674878 1.100074)
			(end 0.674878 1.100074)
			(stroke
				(width 0.1)
				(type default)
			)
			(layer "F.Fab")
		)
		(fp_line
			(start -0.674878 -1.100074)
			(end -0.674878 1.100074)
			(stroke
				(width 0.1)
				(type default)
			)
			(layer "F.Fab")
		)
		(pad "D" smd rect
			(at 0.8001 0 90)
			(size 0.6096 0.8128)
			(layers "F.Cu" "F.Mask" "F.Paste")
			(net "U409_D1")
		)
		(pad "G" smd rect
			(at -0.8001 -0.649986 90)
			(size 0.6096 0.8128)
			(layers "F.Cu" "F.Mask" "F.Paste")
			(net "FAN_4_PRESENT")
		)
		(pad "S" smd rect
			(at -0.8001 0.649986 90)
			(size 0.6096 0.8128)
			(layers "F.Cu" "F.Mask" "F.Paste")
			(net "GND")
		)
	)
	(footprint ""
		(layer "F.Cu")
		(at 10.2362 -39.403274 180)
		(property "Reference" "PC22"
			(at -2.401824 -5.99567 0)
			(unlocked yes)
			(layer "F.SilkS")
			(effects
				(font
					(size 0.7874 0.5842)
					(thickness 0.1524)
				)
				(justify left)
			)
		)
		(property "Value" ""
			(at 0 0 180)
			(layer "F.Fab")
			(effects
				(font
					(size 1.27 1.27)
				)
			)
		)
		(duplicate_pad_numbers_are_jumpers no)
		(fp_line
			(start 5.249926 5.249926)
			(end 5.249926 1.2446)
			(stroke
				(width 0.1524)
				(type default)
			)
			(layer "F.SilkS")
		)
		(fp_line
			(start 5.249926 -1.2446)
			(end 5.249926 -5.249926)
			(stroke
				(width 0.1524)
				(type default)
			)
			(layer "F.SilkS")
		)
		(fp_line
			(start 5.249926 -5.249926)
			(end -3.979926 -5.249926)
			(stroke
				(width 0.1524)
				(type default)
			)
			(layer "F.SilkS")
		)
		(fp_line
			(start -3.979926 5.249926)
			(end 5.249926 5.249926)
			(stroke
				(width 0.1524)
				(type default)
			)
			(layer "F.SilkS")
		)
		(fp_line
			(start -3.979926 -5.249926)
			(end -5.249926 -3.979926)
			(stroke
				(width 0.1524)
				(type default)
			)
			(layer "F.SilkS")
		)
		(fp_line
			(start -5.249926 3.979926)
			(end -3.979926 5.249926)
			(stroke
				(width 0.1524)
				(type default)
			)
			(layer "F.SilkS")
		)
		(fp_line
			(start -5.249926 1.2446)
			(end -5.249926 3.979926)
			(stroke
				(width 0.1524)
				(type default)
			)
			(layer "F.SilkS")
		)
		(fp_line
			(start -5.249926 -3.979926)
			(end -5.249926 -1.2446)
			(stroke
				(width 0.1524)
				(type default)
			)
			(layer "F.SilkS")
		)
		(fp_line
			(start 5.249926 5.249926)
			(end 5.249926 -5.249926)
			(stroke
				(width 0.1)
				(type default)
			)
			(layer "F.Fab")
		)
		(fp_line
			(start 5.249926 -5.249926)
			(end -5.249926 -5.249926)
			(stroke
				(width 0.1)
				(type default)
			)
			(layer "F.Fab")
		)
		(fp_line
			(start -5.249926 5.249926)
			(end 5.249926 5.249926)
			(stroke
				(width 0.1)
				(type default)
			)
			(layer "F.Fab")
		)
		(fp_line
			(start -5.249926 -5.249926)
			(end -5.249926 5.249926)
			(stroke
				(width 0.1)
				(type default)
			)
			(layer "F.Fab")
		)
		(pad "1" smd rect
			(at -4.45008 0 270)
			(size 2.2098 4.4196)
			(layers "F.Cu" "F.Mask" "F.Paste")
			(net "P52V_FAN_4")
		)
		(pad "2" smd rect
			(at 4.45008 0 270)
			(size 2.2098 4.4196)
			(layers "F.Cu" "F.Mask" "F.Paste")
			(net "GND")
		)
	)
	(footprint ""
		(layer "F.Cu")
		(at 3.81 -99.822)
		(property "Reference" "R5659"
			(at 0 0 0)
			(layer "F.SilkS")
			(hide yes)
			(effects
				(font
					(size 1.27 1.27)
				)
			)
		)
		(property "Value" ""
			(at 0 0 0)
			(layer "F.Fab")
			(effects
				(font
					(size 1.27 1.27)
				)
			)
		)
		(duplicate_pad_numbers_are_jumpers no)
		(fp_line
			(start -0.7874 -0.4064)
			(end 0.7874 -0.4064)
			(stroke
				(width 0.1524)
				(type default)
			)
			(layer "F.SilkS")
		)
		(fp_line
			(start -0.7874 0.4064)
			(end -0.7874 -0.4064)
			(stroke
				(width 0.1524)
				(type default)
			)
			(layer "F.SilkS")
		)
		(fp_line
			(start 0.7874 -0.4064)
			(end 0.7874 0.4064)
			(stroke
				(width 0.1524)
				(type default)
			)
			(layer "F.SilkS")
		)
		(fp_line
			(start 0.7874 0.4064)
			(end -0.7874 0.4064)
			(stroke
				(width 0.1524)
				(type default)
			)
			(layer "F.SilkS")
		)
		(fp_line
			(start -0.67945 -0.305054)
			(end -0.12065 -0.305054)
			(stroke
				(width 0.1)
				(type default)
			)
			(layer "F.Fab")
		)
		(fp_line
			(start -0.67945 0.3048)
			(end -0.67945 -0.305054)
			(stroke
				(width 0.1)
				(type default)
			)
			(layer "F.Fab")
		)
		(fp_line
			(start -0.12065 -0.305054)
			(end -0.12065 -0.2794)
			(stroke
				(width 0.1)
				(type default)
			)
			(layer "F.Fab")
		)
		(fp_line
			(start -0.12065 -0.2794)
			(end 0.12065 -0.2794)
			(stroke
				(width 0.1)
				(type default)
			)
			(layer "F.Fab")
		)
		(fp_line
			(start -0.12065 0.2794)
			(end -0.12065 0.3048)
			(stroke
				(width 0.1)
				(type default)
			)
			(layer "F.Fab")
		)
		(fp_line
			(start -0.12065 0.3048)
			(end -0.67945 0.3048)
			(stroke
				(width 0.1)
				(type default)
			)
			(layer "F.Fab")
		)
		(fp_line
			(start 0.120396 0.2794)
			(end -0.12065 0.2794)
			(stroke
				(width 0.1)
				(type default)
			)
			(layer "F.Fab")
		)
		(fp_line
			(start 0.120396 0.3048)
			(end 0.120396 0.2794)
			(stroke
				(width 0.1)
				(type default)
			)
			(layer "F.Fab")
		)
		(fp_line
			(start 0.12065 -0.3048)
			(end 0.67945 -0.3048)
			(stroke
				(width 0.1)
				(type default)
			)
			(layer "F.Fab")
		)
		(fp_line
			(start 0.12065 -0.2794)
			(end 0.12065 -0.3048)
			(stroke
				(width 0.1)
				(type default)
			)
			(layer "F.Fab")
		)
		(fp_line
			(start 0.67945 -0.3048)
			(end 0.67945 0.3048)
			(stroke
				(width 0.1)
				(type default)
			)
			(layer "F.Fab")
		)
		(fp_line
			(start 0.67945 0.3048)
			(end 0.120396 0.3048)
			(stroke
				(width 0.1)
				(type default)
			)
			(layer "F.Fab")
		)
		(pad "1" smd rect
			(at -0.40005 0 180)
			(size 0.4572 0.508)
			(layers "F.Cu" "F.Mask" "F.Paste")
			(net "P12V_LED")
		)
		(pad "2" smd rect
			(at 0.40005 0 180)
			(size 0.4572 0.508)
			(layers "F.Cu" "F.Mask" "F.Paste")
			(net "U410_D1")
		)
	)
	(footprint ""
		(layer "F.Cu")
		(at 36.322 -288.29)
		(property "Reference" "D132"
			(at 2.286 1.04267 0)
			(unlocked yes)
			(layer "F.SilkS")
			(effects
				(font
					(size 0.7874 0.5842)
					(thickness 0.1524)
				)
				(justify left)
			)
		)
		(property "Value" ""
			(at 0 0 0)
			(layer "F.Fab")
			(effects
				(font
					(size 1.27 1.27)
				)
			)
		)
		(duplicate_pad_numbers_are_jumpers no)
		(fp_line
			(start -0.299974 -0.500126)
			(end -0.299974 0.500126)
			(stroke
				(width 0.1524)
				(type default)
			)
			(layer "F.SilkS")
		)
		(fp_line
			(start -0.299974 0.500126)
			(end 0.199898 0)
			(stroke
				(width 0.1524)
				(type default)
			)
			(layer "F.SilkS")
		)
		(fp_line
			(start 0.199898 0)
			(end -0.299974 -0.500126)
			(stroke
				(width 0.1524)
				(type default)
			)
			(layer "F.SilkS")
		)
		(fp_line
			(start 0.299974 -0.500126)
			(end 0.299974 0.500126)
			(stroke
				(width 0.1524)
				(type default)
			)
			(layer "F.SilkS")
		)
		(fp_line
			(start 1.651 -0.6858)
			(end 1.651 0.6858)
			(stroke
				(width 0.1524)
				(type default)
			)
			(layer "F.SilkS")
		)
		(fp_line
			(start 1.778 0.6858)
			(end 1.778 -0.6858)
			(stroke
				(width 0.1524)
				(type default)
			)
			(layer "F.SilkS")
		)
		(fp_line
			(start -1.35001 -0.225044)
			(end -0.899922 -0.225044)
			(stroke
				(width 0.1)
				(type default)
			)
			(layer "F.Fab")
		)
		(fp_line
			(start -1.35001 0.175006)
			(end -1.35001 -0.225044)
			(stroke
				(width 0.1)
				(type default)
			)
			(layer "F.Fab")
		)
		(fp_line
			(start -0.899922 -0.700024)
			(end 0.899922 -0.700024)
			(stroke
				(width 0.1)
				(type default)
			)
			(layer "F.Fab")
		)
		(fp_line
			(start -0.899922 -0.225044)
			(end -0.899922 -0.700024)
			(stroke
				(width 0.1)
				(type default)
			)
			(layer "F.Fab")
		)
		(fp_line
			(start -0.899922 0.175006)
			(end -1.35001 0.175006)
			(stroke
				(width 0.1)
				(type default)
			)
			(layer "F.Fab")
		)
		(fp_line
			(start -0.899922 0.700024)
			(end -0.899922 0.175006)
			(stroke
				(width 0.1)
				(type default)
			)
			(layer "F.Fab")
		)
		(fp_line
			(start -0.299974 -0.500126)
			(end -0.299974 0.500126)
			(stroke
				(width 0.1)
				(type default)
			)
			(layer "F.Fab")
		)
		(fp_line
			(start -0.299974 0.500126)
			(end 0.199898 0)
			(stroke
				(width 0.1)
				(type default)
			)
			(layer "F.Fab")
		)
		(fp_line
			(start 0.199898 0)
			(end -0.299974 -0.500126)
			(stroke
				(width 0.1)
				(type default)
			)
			(layer "F.Fab")
		)
		(fp_line
			(start 0.299974 -0.500126)
			(end 0.299974 0.500126)
			(stroke
				(width 0.1)
				(type default)
			)
			(layer "F.Fab")
		)
		(fp_line
			(start 0.899922 -0.700024)
			(end 0.899922 -0.225044)
			(stroke
				(width 0.1)
				(type default)
			)
			(layer "F.Fab")
		)
		(fp_line
			(start 0.899922 -0.225044)
			(end 1.35001 -0.225044)
			(stroke
				(width 0.1)
				(type default)
			)
			(layer "F.Fab")
		)
		(fp_line
			(start 0.899922 0.175006)
			(end 0.899922 0.700024)
			(stroke
				(width 0.1)
				(type default)
			)
			(layer "F.Fab")
		)
		(fp_line
			(start 0.899922 0.700024)
			(end -0.899922 0.700024)
			(stroke
				(width 0.1)
				(type default)
			)
			(layer "F.Fab")
		)
		(fp_line
			(start 1.35001 -0.225044)
			(end 1.35001 0.175006)
			(stroke
				(width 0.1)
				(type default)
			)
			(layer "F.Fab")
		)
		(fp_line
			(start 1.35001 0.175006)
			(end 0.899922 0.175006)
			(stroke
				(width 0.1)
				(type default)
			)
			(layer "F.Fab")
		)
		(fp_text user "+"
			(at -2.3368 1.12395 0)
			(unlocked yes)
			(layer "F.SilkS")
			(effects
				(font
					(size 1.905 1.4224)
					(thickness 0.1524)
				)
				(justify left)
			)
		)
		(fp_text user "-"
			(at 0.889 0.79375 0)
			(unlocked yes)
			(layer "F.SilkS")
			(effects
				(font
					(size 1.905 1.4224)
					(thickness 0.1524)
				)
				(justify left)
			)
		)
		(fp_text user "+"
			(at -2.794 -0.19685 0)
			(unlocked yes)
			(layer "F.Fab")
			(effects
				(font
					(size 1.905 1.4224)
					(thickness 0.1524)
				)
				(justify left)
			)
		)
		(fp_text user "-"
			(at 1.8288 -0.24765 0)
			(unlocked yes)
			(layer "F.Fab")
			(effects
				(font
					(size 1.905 1.4224)
					(thickness 0.1524)
				)
				(justify left)
			)
		)
		(pad "1" smd rect
			(at -1.0922 0 180)
			(size 0.8128 0.8636)
			(layers "F.Cu" "F.Mask" "F.Paste")
			(net "FAN_0_TACH_OL_R")
		)
		(pad "2" smd rect
			(at 1.0922 0)
			(size 0.8128 0.8636)
			(layers "F.Cu" "F.Mask" "F.Paste")
			(net "FAN_0_TACH_OL_D")
		)
	)
	(footprint ""
		(layer "F.Cu")
		(at 20.828 -136.017 -90)
		(property "Reference" "R4851"
			(at 0 0 270)
			(layer "F.SilkS")
			(hide yes)
			(effects
				(font
					(size 1.27 1.27)
				)
			)
		)
		(property "Value" ""
			(at 0 0 270)
			(layer "F.Fab")
			(effects
				(font
					(size 1.27 1.27)
				)
			)
		)
		(duplicate_pad_numbers_are_jumpers no)
		(fp_line
			(start -0.7874 0.4064)
			(end -0.7874 -0.4064)
			(stroke
				(width 0.1524)
				(type default)
			)
			(layer "F.SilkS")
		)
		(fp_line
			(start 0.7874 0.4064)
			(end -0.7874 0.4064)
			(stroke
				(width 0.1524)
				(type default)
			)
			(layer "F.SilkS")
		)
		(fp_line
			(start -0.7874 -0.4064)
			(end 0.7874 -0.4064)
			(stroke
				(width 0.1524)
				(type default)
			)
			(layer "F.SilkS")
		)
		(fp_line
			(start 0.7874 -0.4064)
			(end 0.7874 0.4064)
			(stroke
				(width 0.1524)
				(type default)
			)
			(layer "F.SilkS")
		)
		(fp_line
			(start -0.67945 0.3048)
			(end -0.67945 -0.305054)
			(stroke
				(width 0.1)
				(type default)
			)
			(layer "F.Fab")
		)
		(fp_line
			(start -0.12065 0.3048)
			(end -0.67945 0.3048)
			(stroke
				(width 0.1)
				(type default)
			)
			(layer "F.Fab")
		)
		(fp_line
			(start 0.120396 0.3048)
			(end 0.120396 0.2794)
			(stroke
				(width 0.1)
				(type default)
			)
			(layer "F.Fab")
		)
		(fp_line
			(start 0.67945 0.3048)
			(end 0.120396 0.3048)
			(stroke
				(width 0.1)
				(type default)
			)
			(layer "F.Fab")
		)
		(fp_line
			(start -0.12065 0.2794)
			(end -0.12065 0.3048)
			(stroke
				(width 0.1)
				(type default)
			)
			(layer "F.Fab")
		)
		(fp_line
			(start 0.120396 0.2794)
			(end -0.12065 0.2794)
			(stroke
				(width 0.1)
				(type default)
			)
			(layer "F.Fab")
		)
		(fp_line
			(start -0.12065 -0.2794)
			(end 0.12065 -0.2794)
			(stroke
				(width 0.1)
				(type default)
			)
			(layer "F.Fab")
		)
		(fp_line
			(start 0.12065 -0.2794)
			(end 0.12065 -0.3048)
			(stroke
				(width 0.1)
				(type default)
			)
			(layer "F.Fab")
		)
		(fp_line
			(start 0.12065 -0.3048)
			(end 0.67945 -0.3048)
			(stroke
				(width 0.1)
				(type default)
			)
			(layer "F.Fab")
		)
		(fp_line
			(start 0.67945 -0.3048)
			(end 0.67945 0.3048)
			(stroke
				(width 0.1)
				(type default)
			)
			(layer "F.Fab")
		)
		(fp_line
			(start -0.67945 -0.305054)
			(end -0.12065 -0.305054)
			(stroke
				(width 0.1)
				(type default)
			)
			(layer "F.Fab")
		)
		(fp_line
			(start -0.12065 -0.305054)
			(end -0.12065 -0.2794)
			(stroke
				(width 0.1)
				(type default)
			)
			(layer "F.Fab")
		)
		(pad "1" smd circle
			(at -0.40005 0 270)
			(size 0 0)
			(layers "F.Cu" "F.Mask" "F.Paste")
			(net "GND")
		)
		(pad "2" smd circle
			(at 0.40005 0 270)
			(size 0 0)
			(layers "F.Cu" "F.Mask" "F.Paste")
			(net "MAX31790_U330_ADD1")
		)
	)
)
